(kicad_pcb
	(version 20221018)
	(generator pcbnew)
	(general
    (thickness 1.62)
  )
	(paper "A4")
	(title_block
    (title "ECP5 - Datacenter Secure Control Module (DC-SCM)")
    (date "2024-07-01")
    (rev "1.2.1")
		(comment 9 "footprints 204-205 of 506")
	)
	(layers
    (0 "F.Cu" signal)
    (1 "In1.Cu" power)
    (2 "In2.Cu" signal)
    (3 "In3.Cu" power)
    (4 "In4.Cu" power)
    (5 "In5.Cu" signal)
    (6 "In6.Cu" power)
    (31 "B.Cu" signal)
    (32 "B.Adhes" user "B.Adhesive")
    (33 "F.Adhes" user "F.Adhesive")
    (34 "B.Paste" user)
    (35 "F.Paste" user)
    (36 "B.SilkS" user "B.Silkscreen")
    (37 "F.SilkS" user "F.Silkscreen")
    (38 "B.Mask" user)
    (39 "F.Mask" user)
    (40 "Dwgs.User" user "User.Drawings")
    (41 "Cmts.User" user "User.Comments")
    (42 "Eco1.User" user "User.Eco1")
    (43 "Eco2.User" user "User.Eco2")
    (44 "Edge.Cuts" user)
    (45 "Margin" user)
    (46 "B.CrtYd" user "B.Courtyard")
    (47 "F.CrtYd" user "F.Courtyard")
    (48 "B.Fab" user)
    (49 "F.Fab" user)
  )
	(footprint "antmicro-footprints:oshw-logo"
		(layer "F.Cu")
    (at 100.6 147.3)
    (descr "OSHW Logo")
    (tags "OSHW Logo")
    (property "Author" "Antmicro")
    (property "License" "Apache-2.0")
    (property "MPN" "")
    (property "Manufacturer" "")
    (property "Public" "False")
    (property "Sheetfile" "ecp5-dc-scm.kicad_sch")
    (property "Sheetname" "")
    (property "ki_description" "Mechanical part")
    (attr exclude_from_pos_files allow_soldermask_bridges)
    (fp_text reference "N2" (at -3.08 -4.76) (layer "F.SilkS") hide
        (effects (font (size 0.7 0.7) (thickness 0.127)))
    )
    (fp_text value "oshw_logo" (at 3.43 -4.88) (layer "F.SilkS") hide
        (effects (font (size 1.524 1.524) (thickness 0.3)))
    )
  )
	(footprint "antmicro-footprints:Oscillator_SMD_ECS_2016MV_2x1.6x0.85mm" (layer "F.Cu")
    (at 111.737 95.366 180)
    (property "Author" "Antmicro")
    (property "License" "Apache-2.0")
    (property "MPN" "ECS-2016MV-250-CN-TR")
    (property "Manufacturer" "ECS Inc. International")
    (property "Sheetfile" "ethernet.kicad_sch")
    (property "Sheetname" "Ethernet")
    (property "Val" "25 MHz")
    (property "ki_description" "Oscillator, 25 MHz, HCMOS, SMD, 2mm x 1.6mm, MultiVolt ECS-2016MV Series")
    (property "ki_keywords" "OSCILLATOR")
    (attr smd)
    (fp_text reference "Y5" (at -2.083 -0.734 90) (layer "F.SilkS")
        (effects (font (size 0.7 0.7) (thickness 0.15)) (justify left bottom))
    )
    (fp_text value "Oscillator_25MHz_ESC_2016MV" (at 0 2.2) (layer "F.Fab")
        (effects (font (size 0.7 0.7) (thickness 0.15)) (justify right bottom))
    )
    (fp_text user "Author: Antmicro" (at -1.05 4.6) (layer "F.Fab") hide
        (effects (font (size 0.7 0.7) (thickness 0.15)) (justify right bottom))
    )
    (fp_text user "${REFERENCE}" (at -1.05 3.4) (layer "F.Fab") hide
        (effects (font (size 0.7 0.7) (thickness 0.15)) (justify right bottom))
    )
    (fp_text user "License: Apache-2.0" (at -1.05 5.8) (layer "F.Fab") hide
        (effects (font (size 0.7 0.7) (thickness 0.15)) (justify right bottom))
    )
    (fp_line (start -0.95 0.4) (end -0.95 -0.4)
      (stroke (width 0.15) (type solid)) (layer "F.SilkS"))
    (fp_line (start -0.4 -1.15) (end 0.4 -1.15)
      (stroke (width 0.15) (type solid)) (layer "F.SilkS"))
    (fp_line (start -0.4 1.15) (end 0.4 1.15)
      (stroke (width 0.15) (type solid)) (layer "F.SilkS"))
    (fp_line (start 0.95 0.4) (end 0.95 -0.4)
      (stroke (width 0.15) (type solid)) (layer "F.SilkS"))
    (fp_circle (center -0.95 -1.15) (end -0.9 -1.15)
      (stroke (width 0.15) (type solid)) (fill solid) (layer "F.SilkS"))
    (fp_rect (start -1.05 -1.25) (end 1.05 1.24)
      (stroke (width 0.05) (type solid)) (fill none) (layer "F.CrtYd"))
    (fp_rect (start -0.85 -1.054) (end 0.852 1.054)
      (stroke (width 0.15) (type solid)) (fill none) (layer "F.Fab"))
    (pad "1" smd rect (at -0.486 -0.637 180) (size 0.6858 0.7874) (layers "F.Cu" "F.Paste" "F.Mask")
      (net 2 "VCC3V3") (pinfunction "EN") (pintype "input"))
    (pad "2" smd rect (at -0.486 0.636 180) (size 0.6858 0.7874) (layers "F.Cu" "F.Paste" "F.Mask")
      (net 1 "GND") (pinfunction "GND") (pintype "power_in"))
    (pad "3" smd rect (at 0.487 0.636 180) (size 0.6858 0.7874) (layers "F.Cu" "F.Paste" "F.Mask")
      (net 676 "/Ethernet/PHY_CLK") (pinfunction "OUT") (pintype "output"))
    (pad "4" smd rect (at 0.487 -0.637 180) (size 0.6858 0.7874) (layers "F.Cu" "F.Paste" "F.Mask")
      (net 2 "VCC3V3") (pinfunction "VDD") (pintype "power_in"))
  )
)
